# BASEBOARD_FAB2 (Tioga Pass) — schematic parts with pin connectivity, parts 2378–2385 of 4751; source: Cadence DE-HDL packaged netlist (pstxprt.dat, pstxnet.dat, pstchip.dat)

J6U2  SCONN288_H44441003  SCONN  pkg PIP  page 48
  1  \12v\(1)  = P12V_NVDIMM_ABC
  2  VSS(93)  GROUND  = GND
  3  DQ(4)  BI  = M_C_DQ<4>
  4  VSS(92)  GROUND  = GND
  5  DQ(0)  BI  = M_C_DQ<0>
  6  VSS(91)  GROUND  = GND
  7  DQS9P  BI  = M_C_DQS_DP<9>
  8  DQS9N  BI  = M_C_DQS_DN<9>
  9  VSS(90)  GROUND  = GND
  10  DQ(6)  BI  = M_C_DQ<6>
  11  VSS(89)  GROUND  = GND
  12  DQ(2)  BI  = M_C_DQ<2>
  13  VSS(88)  GROUND  = GND
  14  DQ(12)  BI  = M_C_DQ<12>
  15  VSS(87)  GROUND  = GND
  16  DQ(8)  BI  = M_C_DQ<8>
  17  VSS(86)  GROUND  = GND
  18  DQS10P  BI  = M_C_DQS_DP<10>
  19  DQS10N  BI  = M_C_DQS_DN<10>
  20  VSS(85)  GROUND  = GND
  21  DQ(14)  BI  = M_C_DQ<14>
  22  VSS(84)  GROUND  = GND
  23  DQ(10)  BI  = M_C_DQ<10>
  24  VSS(83)  GROUND  = GND
  25  DQ(20)  BI  = M_C_DQ<20>
  26  VSS(82)  GROUND  = GND
  27  DQ(16)  BI  = M_C_DQ<16>
  28  VSS(81)  GROUND  = GND
  29  DQS11P  BI  = M_C_DQS_DP<11>
  30  DQS11N  BI  = M_C_DQS_DN<11>
  31  VSS(80)  GROUND  = GND
  32  DQ(22)  BI  = M_C_DQ<22>
  33  VSS(79)  GROUND  = GND
  34  DQ(18)  BI  = M_C_DQ<18>
  35  VSS(78)  GROUND  = GND
  36  DQ(28)  BI  = M_C_DQ<28>
  37  VSS(77)  GROUND  = GND
  38  DQ(24)  BI  = M_C_DQ<24>
  39  VSS(76)  GROUND  = GND
  40  DQS12P  BI  = M_C_DQS_DP<12>
  41  DQS12N  BI  = M_C_DQS_DN<12>
  42  VSS(75)  GROUND  = GND
  43  DQ(30)  BI  = M_C_DQ<30>
  44  VSS(74)  GROUND  = GND
  45  DQ(26)  BI  = M_C_DQ<26>
  46  VSS(73)  GROUND  = GND
  47  CB(4)  BI  = M_C_ECC<4>
  48  VSS(72)  GROUND  = GND
  49  CB(0)  BI  = M_C_ECC<0>
  50  VSS(71)  GROUND  = GND
  51  DQS17P  BI  = M_C_DQS_DP<17>
  52  DQS17N  BI  = M_C_DQS_DN<17>
  53  VSS(70)  GROUND  = GND
  54  CB(6)  BI  = M_C_ECC<6>
  55  VSS(69)  GROUND  = GND
  56  CB(2)  BI  = M_C_ECC<2>
  57  VSS(68)  GROUND  = GND
  58  RESET_N  BI  = M_ABC_RST_N
  59  VDD(25)  POWER  = PVDDQ_ABC
  60  CKE(0)  BI  = M_C_CKE<2>
  61  VDD(24)  POWER  = PVDDQ_ABC
  62  ACT_N  BI  = M_C_ACT_N
  63  BG(0)  BI  = M_C_BG<0>
  64  VDD(23)  POWER  = PVDDQ_ABC
  65  A12  BI  = M_C_MA<12>
  66  A9  BI  = M_C_MA<9>
  67  VDD(22)  POWER  = PVDDQ_ABC
  68  A8  BI  = M_C_MA<8>
  69  A6  BI  = M_C_MA<6>
  70  VDD(21)  POWER  = PVDDQ_ABC
  71  A3  BI  = M_C_MA<3>
  72  A1  BI  = M_C_MA<1>
  73  VDD(20)  POWER  = PVDDQ_ABC
  74  CK0P  BI  = M_C_CLK_DP<2>
  75  CK0N  BI  = M_C_CLK_DN<2>
  76  VDD(19)  POWER  = PVDDQ_ABC
  77  VTT(1)  POWER  = PVTT_ABC
  78  EVENT_N  BI  = FM_DIMM_EVENT_COD_N
  79  A0  BI  = M_C_MA<0>
  80  VDD(18)  POWER  = PVDDQ_ABC
  81  BA(0)  BI  = M_C_BA<0>
  82  A16_RAS_N  BI  = M_C_MA<16>
  83  VDD(17)  POWER  = PVDDQ_ABC
  84  S0_N  BI  = M_C_CS_N<4>
  85  VDD(16)  POWER  = PVDDQ_ABC
  86  A15_CAS_N  BI  = M_C_MA<15>
  87  ODT(0)  BI  = M_C_ODT<2>
  88  VDD(15)  POWER  = PVDDQ_ABC
  89  S1_N  BI  = M_C_CS_N<5>
  90  VDD(14)  POWER  = PVDDQ_ABC
  91  ODT(1)  BI  = M_C_ODT<3>
  92  VDD(13)  POWER  = PVDDQ_ABC
  93  S2_N_C(0)  BI  = M_C_CS_N<6>
  94  VSS(67)  GROUND  = GND
  95  DQ(36)  BI  = M_C_DQ<36>
  96  VSS(66)  GROUND  = GND
  97  DQ(32)  BI  = M_C_DQ<32>
  98  VSS(65)  GROUND  = GND
  99  DQS13P  BI  = M_C_DQS_DP<13>
  100  DQS13N  BI  = M_C_DQS_DN<13>
  101  VSS(64)  GROUND  = GND
  102  DQ(38)  BI  = M_C_DQ<38>
  103  VSS(63)  GROUND  = GND
  104  DQ(34)  BI  = M_C_DQ<34>
  105  VSS(62)  GROUND  = GND
  106  DQ(44)  BI  = M_C_DQ<44>
  107  VSS(61)  GROUND  = GND
  108  DQ(40)  BI  = M_C_DQ<40>
  109  VSS(60)  GROUND  = GND
  110  DQS14P  BI  = M_C_DQS_DP<14>
  111  DQS14N  BI  = M_C_DQS_DN<14>
  112  VSS(59)  GROUND  = GND
  113  DQ(46)  BI  = M_C_DQ<46>
  114  VSS(58)  GROUND  = GND
  115  DQ(42)  BI  = M_C_DQ<42>
  116  VSS(57)  GROUND  = GND
  117  DQ(52)  BI  = M_C_DQ<52>
  118  VSS(56)  GROUND  = GND
  119  DQ(48)  BI  = M_C_DQ<48>
  120  VSS(55)  GROUND  = GND
  121  DQS15P  BI  = M_C_DQS_DP<15>
  122  DQS15N  BI  = M_C_DQS_DN<15>
  123  VSS(54)  GROUND  = GND
  124  DQ(54)  BI  = M_C_DQ<54>
  125  VSS(53)  GROUND  = GND
  126  DQ(50)  BI  = M_C_DQ<50>
  127  VSS(52)  GROUND  = GND
  128  DQ(60)  BI  = M_C_DQ<60>
  129  VSS(51)  GROUND  = GND
  130  DQ(56)  BI  = M_C_DQ<56>
  131  VSS(50)  GROUND  = GND
  132  DQS16P  BI  = M_C_DQS_DP<16>
  133  DQS16N  BI  = M_C_DQS_DN<16>
  134  VSS(49)  GROUND  = GND
  135  DQ(62)  BI  = M_C_DQ<62>
  136  VSS(48)  GROUND  = GND
  137  DQ(58)  BI  = M_C_DQ<58>
  138  VSS(47)  GROUND  = GND
  139  SA(0)  BI  = PVPP_ABC
  140  SA(1)  BI  = GND
  141  SCL  BI  = SMB_DDR_ABC_VPP_SCL
  142  VPP(4)  POWER  = PVPP_ABC
  143  VPP(3)  POWER  = PVPP_ABC
  144  RFU(2)  BI  = TP_CH_C_DIMM_C1_RFU_2
  145  \12v\(0)  = P12V_NVDIMM_ABC
  146  VREFCA  BI  = M_C_VREF
  147  VSS(46)  GROUND  = GND
  148  DQ(5)  BI  = M_C_DQ<5>
  149  VSS(45)  GROUND  = GND
  150  DQ(1)  BI  = M_C_DQ<1>
  151  VSS(44)  GROUND  = GND
  152  DQS0N  BI  = M_C_DQS_DN<0>
  153  DQS0P  BI  = M_C_DQS_DP<0>
  154  VSS(43)  GROUND  = GND
  155  DQ(7)  BI  = M_C_DQ<7>
  156  VSS(42)  GROUND  = GND
  157  DQ(3)  BI  = M_C_DQ<3>
  158  VSS(41)  GROUND  = GND
  159  DQ(13)  BI  = M_C_DQ<13>
  160  VSS(40)  GROUND  = GND
  161  DQ(9)  BI  = M_C_DQ<9>
  162  VSS(39)  GROUND  = GND
  163  DQS1N  BI  = M_C_DQS_DN<1>
  164  DQS1P  BI  = M_C_DQS_DP<1>
  165  VSS(38)  GROUND  = GND
  166  DQ(15)  BI  = M_C_DQ<15>
  167  VSS(37)  GROUND  = GND
  168  DQ(11)  BI  = M_C_DQ<11>
  169  VSS(36)  GROUND  = GND
  170  DQ(21)  BI  = M_C_DQ<21>
  171  VSS(35)  GROUND  = GND
  172  DQ(17)  BI  = M_C_DQ<17>
  173  VSS(34)  GROUND  = GND
  174  DQS2N  BI  = M_C_DQS_DN<2>
  175  DQS2P  BI  = M_C_DQS_DP<2>
  176  VSS(33)  GROUND  = GND
  177  DQ(23)  BI  = M_C_DQ<23>
  178  VSS(32)  GROUND  = GND
  179  DQ(19)  BI  = M_C_DQ<19>
  180  VSS(31)  GROUND  = GND
  181  DQ(29)  BI  = M_C_DQ<29>
  182  VSS(30)  GROUND  = GND
  183  DQ(25)  BI  = M_C_DQ<25>
  184  VSS(29)  GROUND  = GND
  185  DQS3N  BI  = M_C_DQS_DN<3>
  186  DQS3P  BI  = M_C_DQS_DP<3>
  187  VSS(28)  GROUND  = GND
  188  DQ(31)  BI  = M_C_DQ<31>
  189  VSS(27)  GROUND  = GND
  190  DQ(27)  BI  = M_C_DQ<27>
  191  VSS(26)  GROUND  = GND
  192  CB(5)  BI  = M_C_ECC<5>
  193  VSS(25)  GROUND  = GND
  194  CB(1)  BI  = M_C_ECC<1>
  195  VSS(24)  GROUND  = GND
  196  DQS8N  BI  = M_C_DQS_DN<8>
  197  DQS8P  BI  = M_C_DQS_DP<8>
  198  VSS(23)  GROUND  = GND
  199  CB(7)  BI  = M_C_ECC<7>
  200  VSS(22)  GROUND  = GND
  201  CB(3)  BI  = M_C_ECC<3>
  202  VSS(21)  GROUND  = GND
  203  CKE(1)  BI  = M_C_CKE<3>
  204  VDD(12)  POWER  = PVDDQ_ABC
  205  RFU(0)  BI  = TP_CH_C_DIMM_C1_RFU_0
  206  VDD(11)  POWER  = PVDDQ_ABC
  207  BG(1)  BI  = M_C_BG<1>
  208  ALERT_N  BI  = M_C_ALERT_N
  209  VDD(10)  POWER  = PVDDQ_ABC
  210  A11  BI  = M_C_MA<11>
  211  A7  BI  = M_C_MA<7>
  212  VDD(9)  POWER  = PVDDQ_ABC
  213  A5  BI  = M_C_MA<5>
  214  A4  BI  = M_C_MA<4>
  215  VDD(8)  POWER  = PVDDQ_ABC
  216  A2  BI  = M_C_MA<2>
  217  VDD(7)  POWER  = PVDDQ_ABC
  218  CK1P  BI  = M_C_CLK_DP<3>
  219  CK1N  BI  = M_C_CLK_DN<3>
  220  VDD(6)  POWER  = PVDDQ_ABC
  221  VTT(0)  POWER  = PVTT_ABC
  222  PAR  BI  = M_C_PAR
  223  VDD(5)  POWER  = PVDDQ_ABC
  224  BA(1)  BI  = M_C_BA<1>
  225  A10  BI  = M_C_MA<10>
  226  VDD(4)  POWER  = PVDDQ_ABC
  227  RFU(1)  BI  = TP_CH_C_DIMM_C1_RFU_1
  228  A14_WE_N  BI  = M_C_MA<14>
  229  VDD(3)  POWER  = PVDDQ_ABC
  230  SAVE_N_NC  BI  = FM_ADR_COMPLETE_ABC_N
  231  VDD(2)  POWER  = PVDDQ_ABC
  232  A13  BI  = M_C_MA<13>
  233  VDD(1)  POWER  = PVDDQ_ABC
  234  A17  BI  = M_C_MA<17>
  235  C(2)  BI  = M_C_C<2>
  236  VDD(0)  POWER  = PVDDQ_ABC
  237  S3_N_C(1)  BI  = M_C_CS_N<7>
  238  SA(2)  BI  = PVPP_ABC
  239  VSS(20)  GROUND  = GND
  240  DQ(37)  BI  = M_C_DQ<37>
  241  VSS(19)  GROUND  = GND
  242  DQ(33)  BI  = M_C_DQ<33>
  243  VSS(18)  GROUND  = GND
  244  DQS4N  BI  = M_C_DQS_DN<4>
  245  DQS4P  BI  = M_C_DQS_DP<4>
  246  VSS(17)  GROUND  = GND
  247  DQ(39)  BI  = M_C_DQ<39>
  248  VSS(16)  GROUND  = GND
  249  DQ(35)  BI  = M_C_DQ<35>
  250  VSS(15)  GROUND  = GND
  251  DQ(45)  BI  = M_C_DQ<45>
  252  VSS(14)  GROUND  = GND
  253  DQ(41)  BI  = M_C_DQ<41>
  254  VSS(13)  GROUND  = GND
  255  DQS5N  BI  = M_C_DQS_DN<5>
  256  DQS5P  BI  = M_C_DQS_DP<5>
  257  VSS(12)  GROUND  = GND
  258  DQ(47)  BI  = M_C_DQ<47>
  259  VSS(11)  GROUND  = GND
  260  DQ(43)  BI  = M_C_DQ<43>
  261  VSS(10)  GROUND  = GND
  262  DQ(53)  BI  = M_C_DQ<53>
  263  VSS(9)  GROUND  = GND
  264  DQ(49)  BI  = M_C_DQ<49>
  265  VSS(8)  GROUND  = GND
  266  DQS6N  BI  = M_C_DQS_DN<6>
  267  DQS6P  BI  = M_C_DQS_DP<6>
  268  VSS(7)  GROUND  = GND
  269  DQ(55)  BI  = M_C_DQ<55>
  270  VSS(6)  GROUND  = GND
  271  DQ(51)  BI  = M_C_DQ<51>
  272  VSS(5)  GROUND  = GND
  273  DQ(61)  BI  = M_C_DQ<61>
  274  VSS(4)  GROUND  = GND
  275  DQ(57)  BI  = M_C_DQ<57>
  276  VSS(3)  GROUND  = GND
  277  DQS7N  BI  = M_C_DQS_DN<7>
  278  DQS7P  BI  = M_C_DQS_DP<7>
  279  VSS(2)  GROUND  = GND
  280  DQ(63)  BI  = M_C_DQ<63>
  281  VSS(1)  GROUND  = GND
  282  DQ(59)  BI  = M_C_DQ<59>
  283  VSS(0)  GROUND  = GND
  284  VDDSPD  BI  = PVPP_ABC
  285  SDA  BI  = SMB_DDR_ABC_VPP_SDA
  286  VPP(1)  POWER  = PVPP_ABC
  287  VPP(0)  POWER  = PVPP_ABC
  288  VPP(2)  POWER  = PVPP_ABC

J7G2  CONN8_C77962004  CONN  pkg PIP  page 189
  1  IO1  BI  = P3V3_STBY_PLD_D
  2  IO2  BI  = JTAG_TDO_R
  3  IO3  BI  = JTAG_TDI_R
  4  IO4  BI  = JTAG_TRST_N
  5  IO5  BI  = PWRGD_P3V3_STBY
  6  IO6  BI  = JTAG_TMS_R
  7  IO7  BI  = GND
  8  IO8  BI  = JTAG_TCK_R

J7G3  CONN12_C73564003  CONN  pkg PIP  page 136
  1  IO1  BI  = TP_ME_RCVR_BOOT
  2  IO2  BI  = TP_BIOS_USB_RECOVERY
  3  IO3  BI  = FM_ME_RECOVER_N
  4  IO4  BI  = FM_BIOS_USB_RECOVERY
  5  IO5  BI  = PD_ME_RCVR_N
  6  IO6  BI  = PU_BIOS_USB_RECOVERY
  7  IO7  BI  = TP_PASSWORD_CLEAR
  8  IO8  BI  = TP_BIOS_RECOVER_BOOT
  9  IO9  BI  = FM_PASSWORD_CLEAR_N
  10  IO10  BI  = FM_BIOS_TOP_SWAP
  11  IO11  BI  = PD_PASSWORD_CLEAR
  12  IO12  BI  = PU_BIOS_RECOVER_BOOT

J8A1  CONN72_G97614002_A  CONN  pkg CP  page 173
  1A1  SIDEBANDA_7  BI  = TP_FM_QAT_CBL_PRSNT0_R_N
  1A2  SIDEBANDA_0  BI  = SGPIO_PCH_SATA_CLOCK_R
  1A3  GND(23)  GROUND  = GND
  1A4  RXA1_DP  BI  = SATA6G_P1_RX_C_DP
  1A5  RXA1_DN  BI  = SATA6G_P1_RX_C_DN
  1A6  GND(22)  GROUND  = GND
  1A7  RXA3_DP  BI  = SATA6G_P3_RX_C_DP
  1A8  RXA3_DN  BI  = SATA6G_P3_RX_C_DN
  1A9  GND(21)  GROUND  = GND
  1B1  SIDEBANDA_3  BI  = GND
  1B2  SIDEBANDA_1  BI  = SGPIO_PCH_SATA_LOAD_R
  1B3  GND(20)  GROUND  = GND
  1B4  RXA0_DP  BI  = SATA6G_P0_RX_C_DP
  1B5  RXA0_DN  BI  = SATA6G_P0_RX_C_DN
  1B6  GND(19)  GROUND  = GND
  1B7  RXA2_DP  BI  = SATA6G_P2_RX_C_DP
  1B8  RXA2_DN  BI  = SATA6G_P2_RX_C_DN
  1B9  GND(18)  GROUND  = GND
  1C1  SIDEBANDA_4  BI  = SGPIO_PCH_SATA_DOUT0_R
  1C2  SIDEBANDA_2  BI  = GND
  1C3  GND(17)  GROUND  = GND
  1C4  TXA1_DP  BI  = SATA6G_P1_TX_C_DP
  1C5  TXA1_DN  BI  = SATA6G_P1_TX_C_DN
  1C6  GND(16)  GROUND  = GND
  1C7  TXA3_DP  BI  = SATA6G_P3_TX_C_DP
  1C8  TXA3_DN  BI  = SATA6G_P3_TX_C_DN
  1C9  GND(15)  GROUND  = GND
  1D1  SIDEBANDA_5  BI  = PU_DATAIN1_SATA_0_R
  1D2  SIDEBANDA_6  BI  = PD_SATA0_CONTROLLER_TYPE_R
  1D3  GND(14)  GROUND  = GND
  1D4  TXA0_DP  BI  = SATA6G_P0_TX_C_DP
  1D5  TXA0_DN  BI  = SATA6G_P0_TX_C_DN
  1D6  GND(13)  BI  = GND
  1D7  TXA2_DP  BI  = SATA6G_P2_TX_C_DP
  1D8  TXA2_DN  BI  = SATA6G_P2_TX_C_DN
  1D9  GND(12)  GROUND  = GND
  2A1  SIDEBANDB_7  BI  = TP_FM_QAT_CBL_PRSNT1_N_R
  2A2  SIDEBANDB_0  BI  = TP_SGPIO_SATA_CLOCK1_R
  2A3  GND(11)  GROUND  = GND
  2A4  RXB1_DP  BI  = SATA6G_P5_RX_C_DP
  2A5  RXB1_DN  BI  = SATA6G_P5_RX_C_DN
  2A6  GND(10)  GROUND  = GND
  2A7  RXB3_DP  BI  = SATA6G_P7_RX_C_DP
  2A8  RXB3_DN  BI  = SATA6G_P7_RX_C_DN
  2A9  GND(9)  GROUND  = GND
  2B1  SIDEBANDB_3  BI  = GND
  2B2  SIDEBANDB_1  BI  = TP_SGPIO_SATA_LOAD1_R
  2B3  GND(8)  GROUND  = GND
  2B4  RXB0_DP  BI  = SATA6G_P4_RX_C_DP
  2B5  RXB0_DN  BI  = SATA6G_P4_RX_C_DN
  2B6  GND(7)  GROUND  = GND
  2B7  RXB2_DP  BI  = SATA6G_P6_RX_C_DP
  2B8  RXB2_DN  BI  = SATA6G_P6_RX_C_DN
  2B9  GND(6)  GROUND  = GND
  2C1  SIDEBANDB_4  BI  = TP_SGPIO_SATA_DATA1_R
  2C2  SIDEBANDB_2  BI  = GND
  2C3  GND(5)  GROUND  = GND
  2C4  TXB1_DP  BI  = SATA6G_P5_TX_C_DP
  2C5  TXB1_DN  BI  = SATA6G_P5_TX_C_DN
  2C6  GND(4)  GROUND  = GND
  2C7  TXB3_DP  BI  = SATA6G_P7_TX_C_DP
  2C8  TXB3_DN  BI  = SATA6G_P7_TX_C_DN
  2C9  GND(3)  GROUND  = GND
  2D1  SIDEBANDB_5  BI  = PU_DATAIN1_SATA_1_R
  2D2  SIDEBANDB_6  BI  = PD_SATA1_CONTROLLER_TYPE_R
  2D3  GND(2)  GROUND  = GND
  2D4  TXB0_DP  BI  = SATA6G_P4_TX_C_DP
  2D5  TXB0_DN  BI  = SATA6G_P4_TX_C_DN
  2D6  GND(1)  BI  = GND
  2D7  TXB2_DP  BI  = SATA6G_P6_TX_C_DP
  2D8  TXB2_DN  BI  = SATA6G_P6_TX_C_DN
  2D9  GND(0)  GROUND  = GND

J8B1  SCONN24_H46321001  SCONN  pkg SM  page 91
  1  IO1  BI  = GND
  2  IO2  BI  = SMB_HFI0_CPU0_LVC2_SCL
  3  IO3  BI  = FM_MODPRST_HFI0_CPU0_LVT2_N
  4  IO4  BI  = SMB_HFI0_CPU0_LVC2_SDA
  5  IO5  BI  = LED_HFI0_CPU0_N
  6  IO6  BI  = RST_HFI0_CPU0_LVT2_N
  7  IO7  BI  = GND
  8  IO8  BI  = IRQ_HFI0_CPU0_LVT2_N
  9  IO9  BI  = GND
  10  IO10  BI  = SMB_HFI1_CPU0_LVC2_SCL
  11  IO11  BI  = FM_MODPRST_HFI1_CPU0_LVT2_N
  12  IO12  BI  = SMB_HFI1_CPU0_LVC2_SDA
  13  IO13  BI  = LED_HFI1_CPU0_N
  14  IO14  BI  = RST_HFI1_CPU0_LVT2_N
  15  IO15  BI  = GND
  16  IO16  BI  = IRQ_HFI1_CPU0_LVT2_N
  17  IO17  BI  = TP_HFI_IO_CONN0_RSVD_17
  18  IO18  BI  = P3V3
  19  IO19  BI  = PWRGD_PVPP_ABC
  20  IO20  BI  = P3V3
  21  IO21  BI  = PVPP_ABC
  22  IO22  BI  = SMB_OCP_FRU_STBY_LVC3_SCL
  23  IO23  BI  = GND
  24  IO24  BI  = SMB_OCP_FRU_STBY_LVC3_SDA
  MP1  MP1  GROUND  = GND
  MP2  MP2  GROUND  = GND

J8C1  CONN3_C95678002  CONN  pkg PIP  page 156
  1  IO1  UNSPEC  = SMB_HOST_STBY_LVC3_SDA
  2  IO2  UNSPEC  = GND
  3  IO3  UNSPEC  = SMB_HOST_STBY_LVC3_SCL

J8D4  PIN-CON3-27-GP  pkg CONN-G7  page 201
  1  \1\  UNSPEC  = SMB_VR_STBY_LVC3_SDA
  2  \2\  UNSPEC  = GND
  3  \3\  UNSPEC  = SMB_VR_STBY_LVC3_SCL

J8E1  SCONN11_H67026001  CONN  pkg SM  page 184
  1  IO1  BI  = SPI_PCH_TPM_CLK_R
  2  IO2  BI  = RST_PLTRST_BUF_N
  3  IO3  BI  = SPI_PCH_TPM_MOSI_R
  4  IO4  BI  = SPI_PCH_TPM_MISO_R
  5  IO5  BI  = SPI_PCH_TPM_CS_R_N
  6  IO6  BI  = SMB_SENSOR_STBY_LVC3_SDA
  7  IO7  BI  = P3V3_STBY
  8  IO8  BI  = FM_TPM_PRES_RST_N
  9  IO9  BI  = IRQ_SPI_TPM_N_R
  10  IO10  BI  = SMB_SENSOR_STBY_LVC3_SCL
  11  IO11  BI  = GND
  MP1  MP1  GROUND  = GND
  MP2  MP2  GROUND  = GND
